(kicad_pcb
	(version 20260206)
	(generator "pcbnew")
	(generator_version "10.0")
	(general
		(thickness 1.6)
		(legacy_teardrops no)
	)
	(paper "A4")
	(title_block
		(title "panther-plus-userver — 13130-1b_20150205.brd")
		(comment 1 "Honey Badger (Wiwynn) / footprint 406 of 1509 (DIMM2), pads 205-210 of 210")
	)
	(layers
		(0 "F.Cu" signal "TOP")
		(4 "In1.Cu" signal "L2")
		(6 "In2.Cu" signal "L3")
		(8 "In3.Cu" signal "L4")
		(10 "In4.Cu" signal "L5")
		(12 "In5.Cu" signal "L6")
		(14 "In6.Cu" signal "L7")
		(16 "In7.Cu" signal "L8")
		(18 "In8.Cu" signal "L9")
		(20 "In9.Cu" signal "L10")
		(22 "In10.Cu" signal "L11")
		(2 "B.Cu" signal "BOTTOM")
		(9 "F.Adhes" user "F.Adhesive")
		(11 "B.Adhes" user "B.Adhesive")
		(13 "F.Paste" user "Package Geometry/Pastemask Top")
		(15 "B.Paste" user "Package Geometry/Pastemask Bottom")
		(5 "F.SilkS" user "Ref Des/Silkscreen Top")
		(7 "B.SilkS" user "Ref Des/Silkscreen Bottom")
		(1 "F.Mask" user "Board Geometry/Soldermask Top")
		(3 "B.Mask" user "Board Geometry/Soldermask Bottom")
		(17 "Dwgs.User" user "User.Drawings")
		(19 "Cmts.User" user "User.Comments")
		(21 "Eco1.User" user "User.Eco1")
		(23 "Eco2.User" user "User.Eco2")
		(25 "Edge.Cuts" user "Board Geometry/Outline")
		(27 "Margin" user)
		(31 "F.CrtYd" user "Package Geometry/Place Bound Top")
		(29 "B.CrtYd" user "Package Geometry/Place Bound Bottom")
		(35 "F.Fab" user "Ref Des/Assembly Top")
		(33 "B.Fab" user "Ref Des/Assembly Bottom")
	)
	(footprint ""
		(layer "F.Cu")
		(at 158.500064 -66.699892 180)
		(property "Reference" "DIMM2"
			(at 0 0 180)
			(layer "F.SilkS")
			(hide yes)
			(effects
				(font
					(size 1.27 1.27)
				)
			)
		)
		(property "Value" "DDR3-204P-174-COLAY-1-GP"
			(at -40.682164 -17.468088 180)
			(unlocked yes)
			(layer "F.Fab")
			(hide yes)
			(effects
				(font
					(size 1.016 1.016)
					(thickness 0.1524)
				)
			)
		)
		(property "Device Type" "AS0A626-H8SN-7H-COLAY-1"
			(at -40.682164 -18.992088 180)
			(unlocked yes)
			(layer "F.Fab")
			(hide yes)
			(effects
				(font
					(size 1.016 1.016)
					(thickness 0.1524)
				)
			)
		)
		(duplicate_pad_numbers_are_jumpers no)
		(pad "203" smd custom
			(at 31.34995 4.106672 180)
			(size 0.1143 0.1143)
			(layers "F.Cu" "F.Mask" "F.Paste")
			(net "PV_VTT_DDR_A")
			(options
				(clearance outline)
				(anchor circle)
			)
			(primitives
				(gr_poly
					(pts
						(xy 0 0.9017) (xy -0.03175 0.89916) (xy -0.0635 0.889) (xy -0.09144 0.87376) (xy -0.11684 0.85344)
						(xy -0.13716 0.82804) (xy -0.1524 0.8001) (xy -0.16256 0.76835) (xy -0.1651 0.7366) (xy -0.1651 0.11938)
						(xy -0.17272 0.11176) (xy -0.19812 0.0762) (xy -0.2032 0.06604) (xy -0.20701 0.05715) (xy -0.21209 0.04699)
						(xy -0.2159 0.03683) (xy -0.21844 0.02667) (xy -0.22225 0.01524) (xy -0.22352 0.00508) (xy -0.22606 -0.00508)
						(xy -0.22733 -0.01651) (xy -0.22733 -0.02667) (xy -0.2286 -0.0381) (xy -0.22733 -0.04953) (xy -0.22733 -0.05969)
						(xy -0.22606 -0.07112) (xy -0.22352 -0.08128) (xy -0.22225 -0.09144) (xy -0.21844 -0.10287) (xy -0.2159 -0.11303)
						(xy -0.21209 -0.12319) (xy -0.20701 -0.13335) (xy -0.2032 -0.14224) (xy -0.19812 -0.1524) (xy -0.17272 -0.18796)
						(xy -0.1651 -0.19558) (xy -0.1651 -0.7366) (xy -0.16256 -0.76835) (xy -0.1524 -0.8001) (xy -0.13716 -0.82804)
						(xy -0.11684 -0.85344) (xy -0.09144 -0.87376) (xy -0.0635 -0.889) (xy -0.03175 -0.89916) (xy 0 -0.9017)
						(xy 0.03175 -0.89916) (xy 0.0635 -0.889) (xy 0.09144 -0.87376) (xy 0.11684 -0.85344) (xy 0.13716 -0.82804)
						(xy 0.1524 -0.8001) (xy 0.16256 -0.76835) (xy 0.1651 -0.7366) (xy 0.1651 -0.19685) (xy 0.17272 -0.18923)
						(xy 0.17907 -0.18034) (xy 0.18669 -0.17145) (xy 0.19177 -0.16256) (xy 0.19812 -0.15367) (xy 0.20828 -0.13335)
						(xy 0.21971 -0.10287) (xy 0.22225 -0.09271) (xy 0.22479 -0.08128) (xy 0.22606 -0.07112) (xy 0.2286 -0.05969)
						(xy 0.2286 -0.01651) (xy 0.22606 -0.00508) (xy 0.22479 0.00508) (xy 0.22225 0.01651) (xy 0.21971 0.02667)
						(xy 0.20828 0.05715) (xy 0.19812 0.07747) (xy 0.19177 0.08636) (xy 0.18669 0.09525) (xy 0.17907 0.10414)
						(xy 0.17272 0.11303) (xy 0.1651 0.12065) (xy 0.1651 0.7366) (xy 0.16256 0.76835) (xy 0.1524 0.8001)
						(xy 0.13716 0.82804) (xy 0.11684 0.85344) (xy 0.09144 0.87376) (xy 0.0635 0.889) (xy 0.03175 0.89916)
					)
					(width 0)
					(fill yes)
				)
			)
		)
		(pad "204" smd custom
			(at 31.649924 -4.106672 180)
			(size 0.1143 0.1143)
			(layers "F.Cu" "F.Mask" "F.Paste")
			(net "PV_VTT_DDR_A")
			(options
				(clearance outline)
				(anchor circle)
			)
			(primitives
				(gr_poly
					(pts
						(xy 0 0.9017) (xy -0.03175 0.89916) (xy -0.0635 0.889) (xy -0.09144 0.87376) (xy -0.11684 0.85344)
						(xy -0.13716 0.82804) (xy -0.1524 0.8001) (xy -0.16256 0.76835) (xy -0.1651 0.7366) (xy -0.1651 0.19685)
						(xy -0.17272 0.18923) (xy -0.17907 0.18034) (xy -0.18669 0.17145) (xy -0.19177 0.16256) (xy -0.19812 0.15367)
						(xy -0.20828 0.13335) (xy -0.21971 0.10287) (xy -0.22225 0.09271) (xy -0.22479 0.08128) (xy -0.22606 0.07112)
						(xy -0.2286 0.05969) (xy -0.2286 0.01651) (xy -0.22606 0.00508) (xy -0.22479 -0.00508) (xy -0.22225 -0.01651)
						(xy -0.21971 -0.02667) (xy -0.20828 -0.05715) (xy -0.19812 -0.07747) (xy -0.19177 -0.08636) (xy -0.18669 -0.09525)
						(xy -0.17907 -0.10414) (xy -0.17272 -0.11303) (xy -0.1651 -0.12065) (xy -0.1651 -0.7366) (xy -0.16256 -0.76835)
						(xy -0.1524 -0.8001) (xy -0.13716 -0.82804) (xy -0.11684 -0.85344) (xy -0.09144 -0.87376) (xy -0.0635 -0.889)
						(xy -0.03175 -0.89916) (xy 0 -0.9017) (xy 0.03175 -0.89916) (xy 0.0635 -0.889) (xy 0.09144 -0.87376)
						(xy 0.11684 -0.85344) (xy 0.13716 -0.82804) (xy 0.1524 -0.8001) (xy 0.16256 -0.76835) (xy 0.1651 -0.7366)
						(xy 0.1651 -0.11938) (xy 0.17272 -0.11176) (xy 0.19812 -0.0762) (xy 0.2032 -0.06604) (xy 0.20701 -0.05715)
						(xy 0.21209 -0.04699) (xy 0.2159 -0.03683) (xy 0.21844 -0.02667) (xy 0.22225 -0.01524) (xy 0.22352 -0.00508)
						(xy 0.22606 0.00508) (xy 0.22733 0.01651) (xy 0.22733 0.02667) (xy 0.2286 0.0381) (xy 0.22733 0.04953)
						(xy 0.22733 0.05969) (xy 0.22606 0.07112) (xy 0.22352 0.08128) (xy 0.22225 0.09144) (xy 0.21844 0.10287)
						(xy 0.2159 0.11303) (xy 0.21209 0.12319) (xy 0.20701 0.13335) (xy 0.2032 0.14224) (xy 0.19812 0.1524)
						(xy 0.17272 0.18796) (xy 0.1651 0.19558) (xy 0.1651 0.7366) (xy 0.16256 0.76835) (xy 0.1524 0.8001)
						(xy 0.13716 0.82804) (xy 0.11684 0.85344) (xy 0.09144 0.87376) (xy 0.0635 0.889) (xy 0.03175 0.89916)
					)
					(width 0)
					(fill yes)
				)
			)
		)
		(pad "205" smd rect
			(at -37.349938 -11.299952 180)
			(size 4.699 6.8072)
			(layers "F.Cu" "F.Mask" "F.Paste")
			(net "GND")
		)
		(pad "206" smd rect
			(at 37.349938 -11.299952 180)
			(size 4.699 6.8072)
			(layers "F.Cu" "F.Mask" "F.Paste")
			(net "GND")
		)
		(pad "207" smd rect
			(at -32.800036 -11.999976 180)
			(size 3.5052 4.5974)
			(layers "F.Cu" "F.Mask" "F.Paste")
			(net "GND")
		)
		(pad "208" smd rect
			(at 32.800036 -11.999976 180)
			(size 3.5052 4.5974)
			(layers "F.Cu" "F.Mask" "F.Paste")
			(net "GND")
		)
	)
)
